(kicad_pcb
	(version 20260206)
	(generator "pcbnew")
	(generator_version "10.0")
	(general
		(thickness 1.6)
		(legacy_teardrops no)
	)
	(paper "A4")
	(title_block
		(title "peb — Lightning_PEB_BRD.brd")
		(comment 1 "Lightning (Wiwynn / Facebook NVMe JBOF) / footprints 1880-1887 of 2563")
	)
	(layers
		(0 "F.Cu" signal "TOP")
		(4 "In1.Cu" signal "L2GND")
		(6 "In2.Cu" signal "L3")
		(8 "In3.Cu" signal "L4VCC")
		(10 "In4.Cu" signal "L5VCC")
		(12 "In5.Cu" signal "L6")
		(14 "In6.Cu" signal "L7GND")
		(2 "B.Cu" signal "BOTTOM")
		(9 "F.Adhes" user "F.Adhesive")
		(11 "B.Adhes" user "B.Adhesive")
		(13 "F.Paste" user "Package Geometry/Pastemask Top")
		(15 "B.Paste" user "Package Geometry/Pastemask Bottom")
		(5 "F.SilkS" user "Ref Des/Silkscreen Top")
		(7 "B.SilkS" user "Ref Des/Silkscreen Bottom")
		(1 "F.Mask" user "Board Geometry/Soldermask Top")
		(3 "B.Mask" user "Board Geometry/Soldermask Bottom")
		(17 "Dwgs.User" user "User.Drawings")
		(19 "Cmts.User" user "User.Comments")
		(21 "Eco1.User" user "User.Eco1")
		(23 "Eco2.User" user "User.Eco2")
		(25 "Edge.Cuts" user "Board Geometry/Outline")
		(27 "Margin" user)
		(31 "F.CrtYd" user "Package Geometry/Place Bound Top")
		(29 "B.CrtYd" user "Package Geometry/Place Bound Bottom")
		(35 "F.Fab" user "Ref Des/Assembly Top")
		(33 "B.Fab" user "Ref Des/Assembly Bottom")
	)
	(footprint ""
		(layer "B.Cu")
		(at 343.154 -71.501 180)
		(property "Reference" "PR162"
			(at 0 0 0)
			(layer "B.SilkS")
			(hide yes)
			(effects
				(font
					(size 1.27 1.27)
				)
				(justify mirror)
			)
		)
		(property "Value" "187KR2F-GP"
			(at -0.064008 -3.993896 180)
			(unlocked yes)
			(layer "B.Fab")
			(hide yes)
			(effects
				(font
					(size 1.016 1.016)
					(thickness 0.1524)
				)
				(justify mirror)
			)
		)
		(property "Device Type" "R402H16"
			(at -0.064008 -5.517896 180)
			(unlocked yes)
			(layer "B.Fab")
			(hide yes)
			(effects
				(font
					(size 1.016 1.016)
					(thickness 0.1524)
				)
				(justify mirror)
			)
		)
		(duplicate_pad_numbers_are_jumpers no)
		(fp_line
			(start 0.508 -0.9398)
			(end 0.508 0.9398)
			(stroke
				(width 0.1524)
				(type default)
			)
			(layer "B.SilkS")
		)
		(fp_line
			(start -0.508 -0.9398)
			(end 0.508 -0.9398)
			(stroke
				(width 0.1524)
				(type default)
			)
			(layer "B.SilkS")
		)
		(fp_rect
			(start 0.508 0.9398)
			(end -0.508 -0.9398)
			(stroke
				(width 0)
				(type default)
			)
			(fill no)
			(layer "B.CrtYd")
		)
		(fp_rect
			(start 0.508 0.9398)
			(end -0.508 -0.9398)
			(stroke
				(width 0)
				(type default)
			)
			(fill no)
			(layer "B.Fab")
		)
		(pad "1" smd custom
			(at 0 -0.4445)
			(size 0.1397 0.1397)
			(layers "B.Cu" "B.Mask" "B.Paste")
			(net "P0V9_E_RF")
			(options
				(clearance outline)
				(anchor circle)
			)
			(primitives
				(gr_poly
					(pts
						(arc
							(start -0.1778 0.2794)
							(mid -0.249642 0.249642)
							(end -0.2794 0.1778)
						)
						(arc
							(start -0.2794 -0.1778)
							(mid -0.249642 -0.249642)
							(end -0.1778 -0.2794)
						)
						(arc
							(start 0.1778 -0.2794)
							(mid 0.249642 -0.249642)
							(end 0.2794 -0.1778)
						)
						(arc
							(start 0.2794 0.1778)
							(mid 0.249642 0.249642)
							(end 0.1778 0.2794)
						)
					)
					(width 0)
					(fill yes)
				)
			)
		)
		(pad "2" smd custom
			(at 0 0.4445)
			(size 0.1397 0.1397)
			(layers "B.Cu" "B.Mask" "B.Paste")
			(net "AGND_P0V9_E")
			(options
				(clearance outline)
				(anchor circle)
			)
			(primitives
				(gr_poly
					(pts
						(arc
							(start -0.1778 0.2794)
							(mid -0.249642 0.249642)
							(end -0.2794 0.1778)
						)
						(arc
							(start -0.2794 -0.1778)
							(mid -0.249642 -0.249642)
							(end -0.1778 -0.2794)
						)
						(arc
							(start 0.1778 -0.2794)
							(mid 0.249642 -0.249642)
							(end 0.2794 -0.1778)
						)
						(arc
							(start 0.2794 0.1778)
							(mid 0.249642 0.249642)
							(end 0.1778 0.2794)
						)
					)
					(width 0)
					(fill yes)
				)
			)
		)
	)
	(footprint ""
		(layer "B.Cu")
		(at 24.139144 -133.671564 90)
		(property "Reference" "R351"
			(at 0 0 90)
			(layer "B.SilkS")
			(hide yes)
			(effects
				(font
					(size 1.27 1.27)
				)
				(justify mirror)
			)
		)
		(property "Value" "3K3R2F-2-GP"
			(at -0.064008 -3.993896 90)
			(unlocked yes)
			(layer "B.Fab")
			(hide yes)
			(effects
				(font
					(size 1.016 1.016)
					(thickness 0.1524)
				)
				(justify mirror)
			)
		)
		(property "Device Type" "R402H16"
			(at -0.064008 -5.517896 90)
			(unlocked yes)
			(layer "B.Fab")
			(hide yes)
			(effects
				(font
					(size 1.016 1.016)
					(thickness 0.1524)
				)
				(justify mirror)
			)
		)
		(duplicate_pad_numbers_are_jumpers no)
		(fp_line
			(start 0.508 -0.9398)
			(end 0.508 0.9398)
			(stroke
				(width 0.1524)
				(type default)
			)
			(layer "B.SilkS")
		)
		(fp_line
			(start -0.508 -0.9398)
			(end 0.508 -0.9398)
			(stroke
				(width 0.1524)
				(type default)
			)
			(layer "B.SilkS")
		)
		(fp_rect
			(start 0.508 0.9398)
			(end -0.508 -0.9398)
			(stroke
				(width 0)
				(type default)
			)
			(fill no)
			(layer "B.CrtYd")
		)
		(fp_rect
			(start 0.508 0.9398)
			(end -0.508 -0.9398)
			(stroke
				(width 0)
				(type default)
			)
			(fill no)
			(layer "B.Fab")
		)
		(pad "1" smd custom
			(at 0 -0.4445 270)
			(size 0.1397 0.1397)
			(layers "B.Cu" "B.Mask" "B.Paste")
			(net "P3V3_STBY")
			(options
				(clearance outline)
				(anchor circle)
			)
			(primitives
				(gr_poly
					(pts
						(arc
							(start -0.1778 0.2794)
							(mid -0.249642 0.249642)
							(end -0.2794 0.1778)
						)
						(arc
							(start -0.2794 -0.1778)
							(mid -0.249642 -0.249642)
							(end -0.1778 -0.2794)
						)
						(arc
							(start 0.1778 -0.2794)
							(mid 0.249642 -0.249642)
							(end 0.2794 -0.1778)
						)
						(arc
							(start 0.2794 0.1778)
							(mid 0.249642 0.249642)
							(end 0.1778 0.2794)
						)
					)
					(width 0)
					(fill yes)
				)
			)
		)
		(pad "2" smd custom
			(at 0 0.4445 270)
			(size 0.1397 0.1397)
			(layers "B.Cu" "B.Mask" "B.Paste")
			(net "ROMA3")
			(options
				(clearance outline)
				(anchor circle)
			)
			(primitives
				(gr_poly
					(pts
						(arc
							(start -0.1778 0.2794)
							(mid -0.249642 0.249642)
							(end -0.2794 0.1778)
						)
						(arc
							(start -0.2794 -0.1778)
							(mid -0.249642 -0.249642)
							(end -0.1778 -0.2794)
						)
						(arc
							(start 0.1778 -0.2794)
							(mid 0.249642 -0.249642)
							(end 0.2794 -0.1778)
						)
						(arc
							(start 0.2794 0.1778)
							(mid 0.249642 0.249642)
							(end 0.1778 0.2794)
						)
					)
					(width 0)
					(fill yes)
				)
			)
		)
	)
	(footprint ""
		(layer "B.Cu")
		(at 233.8832 -36.4236)
		(property "Reference" "TP122"
			(at 0 0 0)
			(layer "B.SilkS")
			(hide yes)
			(effects
				(font
					(size 1.27 1.27)
				)
				(justify mirror)
			)
		)
		(property "Value" "TPAD28-2-GP"
			(at 0.0127 -1.6637 0)
			(unlocked yes)
			(layer "B.Fab")
			(hide yes)
			(effects
				(font
					(size 1.016 1.016)
					(thickness 0.1524)
				)
				(justify mirror)
			)
		)
		(property "Device Type" "TPAD28"
			(at 0.0127 -3.1877 0)
			(unlocked yes)
			(layer "B.Fab")
			(hide yes)
			(effects
				(font
					(size 1.016 1.016)
					(thickness 0.1524)
				)
				(justify mirror)
			)
		)
		(duplicate_pad_numbers_are_jumpers no)
		(fp_poly
			(pts
				(arc
					(start 0.3556 0)
					(mid -0.3556 0)
					(end 0.3556 0)
				)
			)
			(stroke
				(width 0)
				(type default)
			)
			(fill no)
			(layer "B.CrtYd")
		)
		(fp_poly
			(pts
				(arc
					(start 0.6096 0)
					(mid -0.6096 0)
					(end 0.6096 0)
				)
			)
			(stroke
				(width 0)
				(type default)
			)
			(fill no)
			(layer "B.Fab")
		)
		(pad "1" smd circle
			(at 0 0 180)
			(size 0.7112 0.7112)
			(layers "B.Cu" "B.Mask" "B.Paste")
			(net "LBI_ADDR_10")
		)
	)
	(footprint ""
		(layer "B.Cu")
		(at 19.9136 -186.2582 -90)
		(property "Reference" "R2119"
			(at 0 0 90)
			(layer "B.SilkS")
			(hide yes)
			(effects
				(font
					(size 1.27 1.27)
				)
				(justify mirror)
			)
		)
		(property "Value" "10R2F-L-GP"
			(at -0.064008 -3.993896 270)
			(unlocked yes)
			(layer "B.Fab")
			(hide yes)
			(effects
				(font
					(size 1.016 1.016)
					(thickness 0.1524)
				)
				(justify mirror)
			)
		)
		(property "Device Type" "R402H14"
			(at -0.064008 -5.517896 270)
			(unlocked yes)
			(layer "B.Fab")
			(hide yes)
			(effects
				(font
					(size 1.016 1.016)
					(thickness 0.1524)
				)
				(justify mirror)
			)
		)
		(duplicate_pad_numbers_are_jumpers no)
		(fp_line
			(start -0.508 -0.9398)
			(end 0.508 -0.9398)
			(stroke
				(width 0.1524)
				(type default)
			)
			(layer "B.SilkS")
		)
		(fp_line
			(start 0.508 -0.9398)
			(end 0.508 0.9398)
			(stroke
				(width 0.1524)
				(type default)
			)
			(layer "B.SilkS")
		)
		(fp_rect
			(start 0.508 0.9398)
			(end -0.508 -0.9398)
			(stroke
				(width 0)
				(type default)
			)
			(fill no)
			(layer "B.CrtYd")
		)
		(fp_rect
			(start 0.508 0.9398)
			(end -0.508 -0.9398)
			(stroke
				(width 0)
				(type default)
			)
			(fill no)
			(layer "B.Fab")
		)
		(pad "1" smd custom
			(at 0 -0.4445 90)
			(size 0.1397 0.1397)
			(layers "B.Cu" "B.Mask" "B.Paste")
			(net "MB0_CM_SENSE_R1_P")
			(options
				(clearance outline)
				(anchor circle)
			)
			(primitives
				(gr_poly
					(pts
						(arc
							(start -0.1778 0.2794)
							(mid -0.249642 0.249642)
							(end -0.2794 0.1778)
						)
						(arc
							(start -0.2794 -0.1778)
							(mid -0.249642 -0.249642)
							(end -0.1778 -0.2794)
						)
						(arc
							(start 0.1778 -0.2794)
							(mid 0.249642 -0.249642)
							(end 0.2794 -0.1778)
						)
						(arc
							(start 0.2794 0.1778)
							(mid 0.249642 0.249642)
							(end 0.1778 0.2794)
						)
					)
					(width 0)
					(fill yes)
				)
			)
		)
		(pad "2" smd custom
			(at 0 0.4445 90)
			(size 0.1397 0.1397)
			(layers "B.Cu" "B.Mask" "B.Paste")
			(net "MB0_CM_SENSE_P")
			(options
				(clearance outline)
				(anchor circle)
			)
			(primitives
				(gr_poly
					(pts
						(arc
							(start -0.1778 0.2794)
							(mid -0.249642 0.249642)
							(end -0.2794 0.1778)
						)
						(arc
							(start -0.2794 -0.1778)
							(mid -0.249642 -0.249642)
							(end -0.1778 -0.2794)
						)
						(arc
							(start 0.1778 -0.2794)
							(mid 0.249642 -0.249642)
							(end 0.2794 -0.1778)
						)
						(arc
							(start 0.2794 0.1778)
							(mid 0.249642 0.249642)
							(end 0.1778 0.2794)
						)
					)
					(width 0)
					(fill yes)
				)
			)
		)
	)
	(footprint ""
		(layer "B.Cu")
		(at 38.062154 -158.987744 180)
		(property "Reference" "C171"
			(at 0 0 0)
			(layer "B.SilkS")
			(hide yes)
			(effects
				(font
					(size 1.27 1.27)
				)
				(justify mirror)
			)
		)
		(property "Value" "SCD1U16V2KX-3GP"
			(at -1.1811 -2.7051 180)
			(unlocked yes)
			(layer "B.Fab")
			(hide yes)
			(effects
				(font
					(size 1.016 1.016)
					(thickness 0.1524)
				)
				(justify mirror)
			)
		)
		(property "Device Type" "C402H22"
			(at -1.1811 -4.2291 180)
			(unlocked yes)
			(layer "B.Fab")
			(hide yes)
			(effects
				(font
					(size 1.016 1.016)
					(thickness 0.1524)
				)
				(justify mirror)
			)
		)
		(duplicate_pad_numbers_are_jumpers no)
		(fp_rect
			(start 0.4318 0.9525)
			(end -0.4318 -0.9525)
			(stroke
				(width 0)
				(type default)
			)
			(fill no)
			(layer "B.CrtYd")
		)
		(fp_rect
			(start 0.4318 0.9525)
			(end -0.4318 -0.9525)
			(stroke
				(width 0)
				(type default)
			)
			(fill no)
			(layer "B.Fab")
		)
		(pad "1" smd custom
			(at 0 -0.4445)
			(size 0.1524 0.1524)
			(layers "B.Cu" "B.Mask" "B.Paste")
			(net "P1V53_STBY")
			(options
				(clearance outline)
				(anchor circle)
			)
			(primitives
				(gr_poly
					(pts
						(arc
							(start 0.3048 0.2032)
							(mid 0.275042 0.275042)
							(end 0.2032 0.3048)
						)
						(arc
							(start -0.2032 0.3048)
							(mid -0.275042 0.275042)
							(end -0.3048 0.2032)
						)
						(arc
							(start -0.3048 -0.2032)
							(mid -0.275042 -0.275042)
							(end -0.2032 -0.3048)
						)
						(arc
							(start 0.2032 -0.3048)
							(mid 0.275042 -0.275042)
							(end 0.3048 -0.2032)
						)
					)
					(width 0)
					(fill yes)
				)
			)
		)
		(pad "2" smd custom
			(at 0 0.4445)
			(size 0.1524 0.1524)
			(layers "B.Cu" "B.Mask" "B.Paste")
			(net "GND")
			(options
				(clearance outline)
				(anchor circle)
			)
			(primitives
				(gr_poly
					(pts
						(arc
							(start 0.3048 0.2032)
							(mid 0.275042 0.275042)
							(end 0.2032 0.3048)
						)
						(arc
							(start -0.2032 0.3048)
							(mid -0.275042 0.275042)
							(end -0.3048 0.2032)
						)
						(arc
							(start -0.3048 -0.2032)
							(mid -0.275042 -0.275042)
							(end -0.2032 -0.3048)
						)
						(arc
							(start 0.2032 -0.3048)
							(mid 0.275042 -0.275042)
							(end 0.3048 -0.2032)
						)
					)
					(width 0)
					(fill yes)
				)
			)
		)
	)
	(footprint ""
		(layer "B.Cu")
		(at 223.1644 -199.898)
		(property "Reference" "R3226"
			(at 0 0 0)
			(layer "B.SilkS")
			(hide yes)
			(effects
				(font
					(size 1.27 1.27)
				)
				(justify mirror)
			)
		)
		(property "Value" "0R2J-2-GP"
			(at -0.064008 -3.993896 0)
			(unlocked yes)
			(layer "B.Fab")
			(hide yes)
			(effects
				(font
					(size 1.016 1.016)
					(thickness 0.1524)
				)
				(justify mirror)
			)
		)
		(property "Device Type" "R402H16"
			(at -0.064008 -5.517896 0)
			(unlocked yes)
			(layer "B.Fab")
			(hide yes)
			(effects
				(font
					(size 1.016 1.016)
					(thickness 0.1524)
				)
				(justify mirror)
			)
		)
		(duplicate_pad_numbers_are_jumpers no)
		(fp_line
			(start -0.508 -0.9398)
			(end 0.508 -0.9398)
			(stroke
				(width 0.1524)
				(type default)
			)
			(layer "B.SilkS")
		)
		(fp_line
			(start 0.508 -0.9398)
			(end 0.508 0.9398)
			(stroke
				(width 0.1524)
				(type default)
			)
			(layer "B.SilkS")
		)
		(fp_rect
			(start 0.508 0.9398)
			(end -0.508 -0.9398)
			(stroke
				(width 0)
				(type default)
			)
			(fill no)
			(layer "B.CrtYd")
		)
		(fp_rect
			(start 0.508 0.9398)
			(end -0.508 -0.9398)
			(stroke
				(width 0)
				(type default)
			)
			(fill no)
			(layer "B.Fab")
		)
		(pad "1" smd custom
			(at 0 -0.4445 180)
			(size 0.1397 0.1397)
			(layers "B.Cu" "B.Mask" "B.Paste")
			(net "BMC_SSD_RST#8")
			(options
				(clearance outline)
				(anchor circle)
			)
			(primitives
				(gr_poly
					(pts
						(arc
							(start -0.1778 0.2794)
							(mid -0.249642 0.249642)
							(end -0.2794 0.1778)
						)
						(arc
							(start -0.2794 -0.1778)
							(mid -0.249642 -0.249642)
							(end -0.1778 -0.2794)
						)
						(arc
							(start 0.1778 -0.2794)
							(mid 0.249642 -0.249642)
							(end 0.2794 -0.1778)
						)
						(arc
							(start 0.2794 0.1778)
							(mid 0.249642 0.249642)
							(end 0.1778 0.2794)
						)
					)
					(width 0)
					(fill yes)
				)
			)
		)
		(pad "2" smd custom
			(at 0 0.4445 180)
			(size 0.1397 0.1397)
			(layers "B.Cu" "B.Mask" "B.Paste")
			(net "BMC_SSD_RST#0_A8")
			(options
				(clearance outline)
				(anchor circle)
			)
			(primitives
				(gr_poly
					(pts
						(arc
							(start -0.1778 0.2794)
							(mid -0.249642 0.249642)
							(end -0.2794 0.1778)
						)
						(arc
							(start -0.2794 -0.1778)
							(mid -0.249642 -0.249642)
							(end -0.1778 -0.2794)
						)
						(arc
							(start 0.1778 -0.2794)
							(mid 0.249642 -0.249642)
							(end 0.2794 -0.1778)
						)
						(arc
							(start 0.2794 0.1778)
							(mid 0.249642 0.249642)
							(end 0.1778 0.2794)
						)
					)
					(width 0)
					(fill yes)
				)
			)
		)
	)
	(footprint ""
		(layer "B.Cu")
		(at 247.599962 -35.999928)
		(property "Reference" "TP290"
			(at 0 0 0)
			(layer "B.SilkS")
			(hide yes)
			(effects
				(font
					(size 1.27 1.27)
				)
				(justify mirror)
			)
		)
		(property "Value" "TPAD28-2-GP"
			(at 0.0127 -1.6637 0)
			(unlocked yes)
			(layer "B.Fab")
			(hide yes)
			(effects
				(font
					(size 1.016 1.016)
					(thickness 0.1524)
				)
				(justify mirror)
			)
		)
		(property "Device Type" "TPAD28"
			(at 0.0127 -3.1877 0)
			(unlocked yes)
			(layer "B.Fab")
			(hide yes)
			(effects
				(font
					(size 1.016 1.016)
					(thickness 0.1524)
				)
				(justify mirror)
			)
		)
		(duplicate_pad_numbers_are_jumpers no)
		(fp_poly
			(pts
				(arc
					(start 0.3556 0)
					(mid -0.3556 0)
					(end 0.3556 0)
				)
			)
			(stroke
				(width 0)
				(type default)
			)
			(fill no)
			(layer "B.CrtYd")
		)
		(fp_poly
			(pts
				(arc
					(start 0.6096 0)
					(mid -0.6096 0)
					(end 0.6096 0)
				)
			)
			(stroke
				(width 0)
				(type default)
			)
			(fill no)
			(layer "B.Fab")
		)
		(pad "1" smd circle
			(at 0 0 180)
			(size 0.7112 0.7112)
			(layers "B.Cu" "B.Mask" "B.Paste")
			(net "TWI_SDA6")
		)
	)
	(footprint ""
		(layer "B.Cu")
		(at 64.135 -122.301 90)
		(property "Reference" "R245"
			(at 0 0 90)
			(layer "B.SilkS")
			(hide yes)
			(effects
				(font
					(size 1.27 1.27)
				)
				(justify mirror)
			)
		)
		(property "Value" "0R2J-2-GP"
			(at -0.064008 -3.993896 90)
			(unlocked yes)
			(layer "B.Fab")
			(hide yes)
			(effects
				(font
					(size 1.016 1.016)
					(thickness 0.1524)
				)
				(justify mirror)
			)
		)
		(property "Device Type" "R402H16"
			(at -0.064008 -5.517896 90)
			(unlocked yes)
			(layer "B.Fab")
			(hide yes)
			(effects
				(font
					(size 1.016 1.016)
					(thickness 0.1524)
				)
				(justify mirror)
			)
		)
		(duplicate_pad_numbers_are_jumpers no)
		(fp_line
			(start 0.508 -0.9398)
			(end 0.508 0.9398)
			(stroke
				(width 0.1524)
				(type default)
			)
			(layer "B.SilkS")
		)
		(fp_line
			(start -0.508 -0.9398)
			(end 0.508 -0.9398)
			(stroke
				(width 0.1524)
				(type default)
			)
			(layer "B.SilkS")
		)
		(fp_rect
			(start 0.508 0.9398)
			(end -0.508 -0.9398)
			(stroke
				(width 0)
				(type default)
			)
			(fill no)
			(layer "B.CrtYd")
		)
		(fp_rect
			(start 0.508 0.9398)
			(end -0.508 -0.9398)
			(stroke
				(width 0)
				(type default)
			)
			(fill no)
			(layer "B.Fab")
		)
		(pad "1" smd custom
			(at 0 -0.4445 270)
			(size 0.1397 0.1397)
			(layers "B.Cu" "B.Mask" "B.Paste")
			(net "BMC_I2C4_MINI4_SDA_S")
			(options
				(clearance outline)
				(anchor circle)
			)
			(primitives
				(gr_poly
					(pts
						(arc
							(start -0.1778 0.2794)
							(mid -0.249642 0.249642)
							(end -0.2794 0.1778)
						)
						(arc
							(start -0.2794 -0.1778)
							(mid -0.249642 -0.249642)
							(end -0.1778 -0.2794)
						)
						(arc
							(start 0.1778 -0.2794)
							(mid 0.249642 -0.249642)
							(end 0.2794 -0.1778)
						)
						(arc
							(start 0.2794 0.1778)
							(mid 0.249642 0.249642)
							(end 0.1778 0.2794)
						)
					)
					(width 0)
					(fill yes)
				)
			)
		)
		(pad "2" smd custom
			(at 0 0.4445 270)
			(size 0.1397 0.1397)
			(layers "B.Cu" "B.Mask" "B.Paste")
			(net "BMC0_SMB4_DAT")
			(options
				(clearance outline)
				(anchor circle)
			)
			(primitives
				(gr_poly
					(pts
						(arc
							(start -0.1778 0.2794)
							(mid -0.249642 0.249642)
							(end -0.2794 0.1778)
						)
						(arc
							(start -0.2794 -0.1778)
							(mid -0.249642 -0.249642)
							(end -0.1778 -0.2794)
						)
						(arc
							(start 0.1778 -0.2794)
							(mid 0.249642 -0.249642)
							(end 0.2794 -0.1778)
						)
						(arc
							(start 0.2794 0.1778)
							(mid 0.249642 0.249642)
							(end 0.1778 0.2794)
						)
					)
					(width 0)
					(fill yes)
				)
			)
		)
	)
)
